# BASEBOARD_FAB2 (Tioga Pass) — schematic netlist excerpt (pin names and nets, part order shuffled) for the footprints in the layout excerpt that follows; sources: Cadence DE-HDL packaged netlist, KiCad conversion of Wiwynn_Tioga_Pass_MB.brd

C1G15  ST270U2D5VBM-GP  pkg SMD-TCG2  page 225 : \1\ = VR_FET_SW_P12V_STBY_PVDDQ_GHJ ; \2\ = GND
C8B2  CAP_A  22.0UF 4V 20% X6S  pkg 0603V  page 130 : A = P1V8_PCH_STBY ; B = GND

Q4W1  FET_N_DUAL  2N7002DW FET  pkg SMLF  page 102
  SOURCE(0)  = SMB_HOST_STBY_LVC3_SDA_R2
  GATE(0)  = P3V3_DB1200_R1
  DRAIN(0)  = SMB_HOST_STBY_LVC3_SCL
  SOURCE(0)  = SMB_HOST_STBY_LVC3_SCL_R2
  GATE(0)  = P3V3_DB1200_R1
  DRAIN(0)  = SMB_HOST_STBY_LVC3_SDA

(kicad_pcb
	(version 20260206)
	(generator "pcbnew")
	(generator_version "10.0")
	(general
		(thickness 1.6)
		(legacy_teardrops no)
	)
	(paper "A4")
	(title_block
		(title "Wiwynn_Tioga_Pass_MB.brd")
		(comment 1 "Tioga Pass / footprints 477-479 of 4770")
	)
	(layers
		(0 "F.Cu" signal "TOP")
		(4 "In1.Cu" signal "L2GND")
		(6 "In2.Cu" signal "L3")
		(8 "In3.Cu" signal "L4GND")
		(10 "In4.Cu" signal "L5")
		(12 "In5.Cu" signal "L6GND")
		(14 "In6.Cu" signal "L7VCC")
		(16 "In7.Cu" signal "L8VCC")
		(18 "In8.Cu" signal "L9GND")
		(20 "In9.Cu" signal "L10")
		(22 "In10.Cu" signal "L11GND")
		(24 "In11.Cu" signal "L12")
		(26 "In12.Cu" signal "L13GND")
		(2 "B.Cu" signal "BOTTOM")
		(9 "F.Adhes" user "F.Adhesive")
		(11 "B.Adhes" user "B.Adhesive")
		(13 "F.Paste" user "Package Geometry/Pastemask Top")
		(15 "B.Paste" user "Package Geometry/Pastemask Bottom")
		(5 "F.SilkS" user "Ref Des/Silkscreen Top")
		(7 "B.SilkS" user "Ref Des/Silkscreen Bottom")
		(1 "F.Mask" user "Board Geometry/Soldermask Top")
		(3 "B.Mask" user "Board Geometry/Soldermask Bottom")
		(17 "Dwgs.User" user "User.Drawings")
		(19 "Cmts.User" user "User.Comments")
		(21 "Eco1.User" user "User.Eco1")
		(23 "Eco2.User" user "User.Eco2")
		(25 "Edge.Cuts" user "Board Geometry/Outline")
		(27 "Margin" user)
		(31 "F.CrtYd" user "Package Geometry/Place Bound Top")
		(29 "B.CrtYd" user "Package Geometry/Place Bound Bottom")
		(35 "F.Fab" user "Ref Des/Assembly Top")
		(33 "B.Fab" user "Ref Des/Assembly Bottom")
	)
	(footprint ""
		(layer "F.Cu")
		(at -2.8956 -6.98754 -90)
		(property "Reference" "C1G15"
			(at 0 0 270)
			(layer "F.SilkS")
			(hide yes)
			(effects
				(font
					(size 1.27 1.27)
				)
			)
		)
		(property "Value" "*"
			(at -2.3114 0.10795 270)
			(unlocked yes)
			(layer "F.Fab")
			(hide yes)
			(effects
				(font
					(size 0.889 0.889)
					(thickness 0.1524)
				)
			)
		)
		(property "Device Type" "ST270U2D5VBM-GP_SMD-TCG2-ST270A"
			(at -2.3114 -1.41605 270)
			(unlocked yes)
			(layer "F.Fab")
			(hide yes)
			(effects
				(font
					(size 0.889 0.889)
					(thickness 0.1524)
				)
			)
		)
		(duplicate_pad_numbers_are_jumpers no)
		(fp_line
			(start -1.5494 0.4826)
			(end -1.5494 -0.4826)
			(stroke
				(width 0.1524)
				(type default)
			)
			(layer "F.SilkS")
		)
		(fp_line
			(start 1.5494 -0.4826)
			(end 1.5494 0.4826)
			(stroke
				(width 0.1524)
				(type default)
			)
			(layer "F.SilkS")
		)
		(fp_line
			(start -1.0922 -2.35458)
			(end 1.0922 -2.35458)
			(stroke
				(width 0.508)
				(type default)
			)
			(layer "F.SilkS")
		)
		(fp_poly
			(pts
				(xy -1.3462 1.9558) (xy -1.3462 1.905) (xy -1.5494 1.905) (xy -1.5494 -1.905) (xy -1.3462 -1.905)
				(xy -1.3462 -1.9558) (xy 1.3462 -1.9558) (xy 1.3462 -1.905) (xy 1.5494 -1.905) (xy 1.5494 1.905)
				(xy 1.3462 1.905) (xy 1.3462 1.9558)
			)
			(stroke
				(width 0)
				(type default)
			)
			(fill no)
			(layer "F.CrtYd")
		)
		(fp_poly
			(pts
				(xy -1.3462 1.9558) (xy -1.3462 1.905) (xy -1.5494 1.905) (xy -1.5494 -1.905) (xy -1.3462 -1.905)
				(xy -1.3462 -1.9558) (xy 1.3462 -1.9558) (xy 1.3462 -1.905) (xy 1.5494 -1.905) (xy 1.5494 1.905)
				(xy 1.3462 1.905) (xy 1.3462 1.9558)
			)
			(stroke
				(width 0)
				(type default)
			)
			(fill no)
			(layer "F.Fab")
		)
		(pad "1" smd rect
			(at 0 -1.27508 270)
			(size 2.6924 1.3462)
			(layers "F.Cu" "F.Mask" "F.Paste")
			(net "VR_FET_SW_P12V_STBY_PVDDQ_GHJ")
		)
		(pad "2" smd rect
			(at 0 1.27508 270)
			(size 2.6924 1.3462)
			(layers "F.Cu" "F.Mask" "F.Paste")
			(net "GND")
		)
	)
	(footprint ""
		(layer "F.Cu")
		(at 172.280072 -73.839324)
		(property "Reference" "Q4W1"
			(at 0 -1.2065 0)
			(unlocked yes)
			(layer "F.SilkS")
			(effects
				(font
					(size 1.27 0.9652)
					(thickness 0.1524)
				)
				(justify left)
			)
		)
		(property "Value" ""
			(at 0 0 0)
			(layer "F.Fab")
			(effects
				(font
					(size 1.27 1.27)
				)
			)
		)
		(duplicate_pad_numbers_are_jumpers no)
		(fp_circle
			(center -0.643382 -0.50546)
			(end -0.516382 -0.50546)
			(stroke
				(width 0.254)
				(type default)
			)
			(fill no)
			(layer "F.SilkS")
		)
		(fp_poly
			(pts
				(xy 0.21463 -0.450088) (xy 1.56337 -0.450088) (xy 1.56337 1.75006) (xy 0.21463 1.75006)
			)
			(stroke
				(width 0)
				(type default)
			)
			(fill no)
			(layer "F.CrtYd")
		)
		(fp_line
			(start 0.21463 -0.450088)
			(end 1.56337 -0.450088)
			(stroke
				(width 0.1)
				(type default)
			)
			(layer "F.Fab")
		)
		(fp_line
			(start 0.21463 1.75006)
			(end 0.21463 -0.450088)
			(stroke
				(width 0.1)
				(type default)
			)
			(layer "F.Fab")
		)
		(fp_line
			(start 1.56337 -0.450088)
			(end 1.56337 1.75006)
			(stroke
				(width 0.1)
				(type default)
			)
			(layer "F.Fab")
		)
		(fp_line
			(start 1.56337 1.75006)
			(end 0.21463 1.75006)
			(stroke
				(width 0.1)
				(type default)
			)
			(layer "F.Fab")
		)
		(fp_circle
			(center -0.848614 -0.6477)
			(end -0.721614 -0.6477)
			(stroke
				(width 0.254)
				(type default)
			)
			(fill no)
			(layer "F.Fab")
		)
		(pad "1" smd rect
			(at 0 0)
			(size 1.016 0.381)
			(layers "F.Cu" "F.Mask" "F.Paste")
			(net "SMB_HOST_STBY_LVC3_SDA_R2")
		)
		(pad "2" smd rect
			(at 0 0.649986)
			(size 1.016 0.381)
			(layers "F.Cu" "F.Mask" "F.Paste")
			(net "P3V3_DB1200_R1")
		)
		(pad "3" smd rect
			(at 0 1.299972)
			(size 1.016 0.381)
			(layers "F.Cu" "F.Mask" "F.Paste")
			(net "SMB_HOST_STBY_LVC3_SCL")
		)
		(pad "4" smd rect
			(at 1.778 1.299972)
			(size 1.016 0.381)
			(layers "F.Cu" "F.Mask" "F.Paste")
			(net "SMB_HOST_STBY_LVC3_SCL_R2")
		)
		(pad "5" smd rect
			(at 1.778 0.649986)
			(size 1.016 0.381)
			(layers "F.Cu" "F.Mask" "F.Paste")
			(net "P3V3_DB1200_R1")
		)
		(pad "6" smd rect
			(at 1.778 0)
			(size 1.016 0.381)
			(layers "F.Cu" "F.Mask" "F.Paste")
			(net "SMB_HOST_STBY_LVC3_SDA")
		)
	)
	(footprint ""
		(layer "F.Cu")
		(at 399.9738 -130.1496 180)
		(property "Reference" "C8B2"
			(at 0 0 180)
			(layer "F.SilkS")
			(hide yes)
			(effects
				(font
					(size 1.27 1.27)
				)
			)
		)
		(property "Value" ""
			(at 0 0 180)
			(layer "F.Fab")
			(effects
				(font
					(size 1.27 1.27)
				)
			)
		)
		(duplicate_pad_numbers_are_jumpers no)
		(fp_poly
			(pts
				(xy -0.4953 -0.2032) (xy 0.4953 -0.2032) (xy 0.4953 1.6002) (xy -0.4953 1.6002)
			)
			(stroke
				(width 0)
				(type default)
			)
			(fill no)
			(layer "F.CrtYd")
		)
		(fp_line
			(start 0.4953 1.6002)
			(end -0.4953 1.6002)
			(stroke
				(width 0.1)
				(type default)
			)
			(layer "F.Fab")
		)
		(fp_line
			(start 0.4953 -0.2032)
			(end 0.4953 1.6002)
			(stroke
				(width 0.1)
				(type default)
			)
			(layer "F.Fab")
		)
		(fp_line
			(start -0.4953 1.6002)
			(end -0.4953 -0.2032)
			(stroke
				(width 0.1)
				(type default)
			)
			(layer "F.Fab")
		)
		(fp_line
			(start -0.4953 -0.2032)
			(end 0.4953 -0.2032)
			(stroke
				(width 0.1)
				(type default)
			)
			(layer "F.Fab")
		)
		(pad "1" smd rect
			(at 0 0 180)
			(size 0.762 0.889)
			(layers "F.Cu" "F.Mask" "F.Paste")
			(net "P1V8_PCH_STBY")
		)
		(pad "2" smd rect
			(at 0 1.397 180)
			(size 0.762 0.889)
			(layers "F.Cu" "F.Mask" "F.Paste")
			(net "GND")
		)
		(zone
			(layer "F.Cu")
			(hatch none 0.5)
			(connect_pads
				(clearance 0)
			)
			(min_thickness 0.25)
			(keepout
				(tracks not_allowed)
				(vias allowed)
				(pads allowed)
				(copperpour not_allowed)
				(footprints allowed)
			)
			(placement
				(enabled no)
				(sheetname "")
			)
			(fill
				(thermal_gap 0.5)
				(thermal_bridge_width 0.5)
				(island_removal_mode 0)
			)
			(polygon
				(pts
					(xy 400.3548 -130.5941) (xy 399.5928 -130.5941) (xy 399.5928 -131.1021) (xy 400.3548 -131.1021)
				)
			)
		)
	)
)
